# TIMECARD (Time Appliance Project (Time Card)) — schematic netlist excerpt (pin names and nets, part order shuffled) for the footprints in the layout excerpt that follows; sources: Cadence DE-HDL packaged netlist, KiCad conversion of R4006-B0001-02_R01.brd

R334  RESISTOR  1KOHM 1%  pkg SMC_0402R_H016  page 17 : \1\ = UNNAMED_6_LM75BDPTSSOP8_I34_A2 ; \2\ = SG
R286  RESISTOR  4.7KOHM 1%  pkg SMC_0402R_H016  page 25 : \1\ = SG ; \2\ = FPGA_IO_3

(kicad_pcb
	(version 20260206)
	(generator "pcbnew")
	(generator_version "10.0")
	(general
		(thickness 1.6)
		(legacy_teardrops no)
	)
	(paper "A4")
	(title_block
		(title "timecard-production-celestica-r4006 — R4006-B0001-02_R01.brd")
		(comment 1 "Time Appliance Project (Time Card) / footprints 952-953 of 1113")
	)
	(layers
		(0 "F.Cu" signal "TOP")
		(4 "In1.Cu" signal "L02_GND1")
		(6 "In2.Cu" signal "L03_SIG1")
		(8 "In3.Cu" signal "L04_GND2")
		(10 "In4.Cu" signal "L05_VCC1")
		(12 "In5.Cu" signal "L06_VCC2")
		(14 "In6.Cu" signal "L07_GND3")
		(16 "In7.Cu" signal "L08_SIG2")
		(18 "In8.Cu" signal "L09_GND4")
		(2 "B.Cu" signal "BOTTOM")
		(9 "F.Adhes" user "F.Adhesive")
		(11 "B.Adhes" user "B.Adhesive")
		(13 "F.Paste" user "Package Geometry/Pastemask Top")
		(15 "B.Paste" user "Package Geometry/Pastemask Bottom")
		(5 "F.SilkS" user "Ref Des/Silkscreen Top")
		(7 "B.SilkS" user "Ref Des/Silkscreen Bottom")
		(1 "F.Mask" user "Board Geometry/Soldermask Top")
		(3 "B.Mask" user "Board Geometry/Soldermask Bottom")
		(17 "Dwgs.User" user "User.Drawings")
		(19 "Cmts.User" user "User.Comments")
		(21 "Eco1.User" user "User.Eco1")
		(23 "Eco2.User" user "User.Eco2")
		(25 "Edge.Cuts" user "Board Geometry/Outline")
		(27 "Margin" user)
		(31 "F.CrtYd" user "Package Geometry/Place Bound Top")
		(29 "B.CrtYd" user "Package Geometry/Place Bound Bottom")
		(35 "F.Fab" user "Ref Des/Assembly Top")
		(33 "B.Fab" user "Ref Des/Assembly Bottom")
	)
	(footprint ""
		(layer "B.Cu")
		(at 96.5454 -64.2874 90)
		(property "Reference" "R286"
			(at 3.4036 0.31623 270)
			(unlocked yes)
			(layer "B.SilkS")
			(effects
				(font
					(size 0.7874 0.5842)
					(thickness 0.1524)
				)
				(justify mirror)
			)
		)
		(property "Value" "VAL*"
			(at -0.02032 2.13233 90)
			(unlocked yes)
			(layer "B.Fab")
			(hide yes)
			(effects
				(font
					(size 0.7874 0.5842)
					(thickness 0.1524)
				)
				(justify mirror)
			)
		)
		(property "Tolerance" "TOL*"
			(at -0.044704 3.05435 90)
			(unlocked yes)
			(layer "Cmts.User")
			(hide yes)
			(effects
				(font
					(size 0.7874 0.5842)
					(thickness 0.1524)
				)
				(justify mirror)
			)
		)
		(property "User Part Number" "PARTNUM*"
			(at -0.02032 4.024884 90)
			(unlocked yes)
			(layer "Cmts.User")
			(hide yes)
			(effects
				(font
					(size 0.7874 0.5842)
					(thickness 0.1524)
				)
				(justify mirror)
			)
		)
		(property "Device Type" "RESISTOR-G155-14701-01,4.7KOHMA"
			(at -0.008382 1.210564 90)
			(unlocked yes)
			(layer "B.Fab")
			(hide yes)
			(effects
				(font
					(size 0.7874 0.5842)
					(thickness 0.1524)
				)
				(justify mirror)
			)
		)
		(duplicate_pad_numbers_are_jumpers no)
		(fp_line
			(start 1.143 -0.5588)
			(end 1.143 0.5588)
			(stroke
				(width 0.1)
				(type default)
			)
			(layer "B.SilkS")
		)
		(fp_line
			(start -1.143 -0.5588)
			(end 1.143 -0.5588)
			(stroke
				(width 0.1)
				(type default)
			)
			(layer "B.SilkS")
		)
		(fp_line
			(start 1.143 0.5588)
			(end -1.143 0.5588)
			(stroke
				(width 0.1)
				(type default)
			)
			(layer "B.SilkS")
		)
		(fp_line
			(start -1.143 0.5588)
			(end -1.143 -0.5588)
			(stroke
				(width 0.1)
				(type default)
			)
			(layer "B.SilkS")
		)
		(fp_poly
			(pts
				(xy 1.143 0.5588) (xy -1.143 0.5588) (xy -1.143 -0.5588) (xy 1.143 -0.5588)
			)
			(stroke
				(width 0)
				(type default)
			)
			(fill no)
			(layer "B.CrtYd")
		)
		(fp_line
			(start 0.508 -0.3048)
			(end 0.508 0.3048)
			(stroke
				(width 0.1)
				(type default)
			)
			(layer "B.Fab")
		)
		(fp_line
			(start -0.508 -0.3048)
			(end 0.508 -0.3048)
			(stroke
				(width 0.1)
				(type default)
			)
			(layer "B.Fab")
		)
		(fp_line
			(start 0.508 0.3048)
			(end -0.508 0.3048)
			(stroke
				(width 0.1)
				(type default)
			)
			(layer "B.Fab")
		)
		(fp_line
			(start -0.508 0.3048)
			(end -0.508 -0.3048)
			(stroke
				(width 0.1)
				(type default)
			)
			(layer "B.Fab")
		)
		(pad "1" smd rect
			(at 0.5334 0 270)
			(size 0.7112 0.6096)
			(layers "B.Cu" "B.Mask" "B.Paste")
			(net "SG")
		)
		(pad "2" smd rect
			(at -0.5334 0 270)
			(size 0.7112 0.6096)
			(layers "B.Cu" "B.Mask" "B.Paste")
			(net "FPGA_IO_3")
		)
		(zone
			(layer "B.Cu")
			(hatch none 0.5)
			(connect_pads
				(clearance 0)
			)
			(min_thickness 0.25)
			(keepout
				(tracks allowed)
				(vias not_allowed)
				(pads allowed)
				(copperpour not_allowed)
				(footprints allowed)
			)
			(placement
				(enabled no)
				(sheetname "")
			)
			(fill
				(thermal_gap 0.5)
				(thermal_bridge_width 0.5)
				(island_removal_mode 0)
			)
			(polygon
				(pts
					(xy 96.8502 -64.3636) (xy 96.2406 -64.3636) (xy 96.2406 -64.2112) (xy 96.8502 -64.2112)
				)
			)
		)
		(zone
			(layer "B.Cu")
			(hatch none 0.5)
			(connect_pads
				(clearance 0)
			)
			(min_thickness 0.25)
			(keepout
				(tracks not_allowed)
				(vias allowed)
				(pads allowed)
				(copperpour not_allowed)
				(footprints allowed)
			)
			(placement
				(enabled no)
				(sheetname "")
			)
			(fill
				(thermal_gap 0.5)
				(thermal_bridge_width 0.5)
				(island_removal_mode 0)
			)
			(polygon
				(pts
					(xy 96.8502 -64.3636) (xy 96.2406 -64.3636) (xy 96.2406 -64.2112) (xy 96.8502 -64.2112)
				)
			)
		)
	)
	(footprint ""
		(layer "B.Cu")
		(at 7.366 -72.39 90)
		(property "Reference" "R334"
			(at -0.381 2.75463 270)
			(unlocked yes)
			(layer "B.SilkS")
			(effects
				(font
					(size 0.7874 0.5842)
					(thickness 0.1524)
				)
				(justify mirror)
			)
		)
		(property "Value" "VAL*"
			(at -0.02032 2.13233 90)
			(unlocked yes)
			(layer "B.Fab")
			(hide yes)
			(effects
				(font
					(size 0.7874 0.5842)
					(thickness 0.1524)
				)
				(justify mirror)
			)
		)
		(property "Tolerance" "TOL*"
			(at -0.044704 3.05435 90)
			(unlocked yes)
			(layer "Cmts.User")
			(hide yes)
			(effects
				(font
					(size 0.7874 0.5842)
					(thickness 0.1524)
				)
				(justify mirror)
			)
		)
		(property "User Part Number" "PARTNUM*"
			(at -0.02032 4.024884 90)
			(unlocked yes)
			(layer "Cmts.User")
			(hide yes)
			(effects
				(font
					(size 0.7874 0.5842)
					(thickness 0.1524)
				)
				(justify mirror)
			)
		)
		(property "Device Type" "RESISTOR-G155-11001-01,1KOHM,1%"
			(at -0.008382 1.210564 90)
			(unlocked yes)
			(layer "B.Fab")
			(hide yes)
			(effects
				(font
					(size 0.7874 0.5842)
					(thickness 0.1524)
				)
				(justify mirror)
			)
		)
		(duplicate_pad_numbers_are_jumpers no)
		(fp_line
			(start 1.143 -0.5588)
			(end 1.143 0.5588)
			(stroke
				(width 0.1)
				(type default)
			)
			(layer "B.SilkS")
		)
		(fp_line
			(start -1.143 -0.5588)
			(end 1.143 -0.5588)
			(stroke
				(width 0.1)
				(type default)
			)
			(layer "B.SilkS")
		)
		(fp_line
			(start 1.143 0.5588)
			(end -1.143 0.5588)
			(stroke
				(width 0.1)
				(type default)
			)
			(layer "B.SilkS")
		)
		(fp_line
			(start -1.143 0.5588)
			(end -1.143 -0.5588)
			(stroke
				(width 0.1)
				(type default)
			)
			(layer "B.SilkS")
		)
		(fp_rect
			(start 1.143 0.5588)
			(end -1.143 -0.5588)
			(stroke
				(width 0)
				(type default)
			)
			(fill no)
			(layer "B.CrtYd")
		)
		(fp_line
			(start 0.508 -0.3048)
			(end 0.508 0.3048)
			(stroke
				(width 0.1)
				(type default)
			)
			(layer "B.Fab")
		)
		(fp_line
			(start -0.508 -0.3048)
			(end 0.508 -0.3048)
			(stroke
				(width 0.1)
				(type default)
			)
			(layer "B.Fab")
		)
		(fp_line
			(start 0.508 0.3048)
			(end -0.508 0.3048)
			(stroke
				(width 0.1)
				(type default)
			)
			(layer "B.Fab")
		)
		(fp_line
			(start -0.508 0.3048)
			(end -0.508 -0.3048)
			(stroke
				(width 0.1)
				(type default)
			)
			(layer "B.Fab")
		)
		(pad "1" smd rect
			(at 0.5334 0 270)
			(size 0.7112 0.6096)
			(layers "B.Cu" "B.Mask" "B.Paste")
			(net "UNNAMED_6_LM75BDPTSSOP8_I34_A2")
		)
		(pad "2" smd rect
			(at -0.5334 0 270)
			(size 0.7112 0.6096)
			(layers "B.Cu" "B.Mask" "B.Paste")
			(net "SG")
		)
		(zone
			(layer "B.Cu")
			(hatch none 0.5)
			(connect_pads
				(clearance 0)
			)
			(min_thickness 0.25)
			(keepout
				(tracks allowed)
				(vias not_allowed)
				(pads allowed)
				(copperpour not_allowed)
				(footprints allowed)
			)
			(placement
				(enabled no)
				(sheetname "")
			)
			(fill
				(thermal_gap 0.5)
				(thermal_bridge_width 0.5)
				(island_removal_mode 0)
			)
			(polygon
				(pts
					(xy 7.6708 -72.4662) (xy 7.0612 -72.4662) (xy 7.0612 -72.3138) (xy 7.6708 -72.3138)
				)
			)
		)
	)
)
